FILE_TYPE = CONNECTIVITY;
{Allegro Design Entry HDL 16.6-p007 (v16-6-112F) 10/10/2012}
"PAGE_NUMBER" = 235;
0"NC";
1"P3V3_STBY\g";
2"GND\g";
3"GND\g";
4"GND\g";
5"GND\g";
6"P3V3_STBY\g";
7"GND\g";
8"GND\g";
9"GND\g";
10"GND\g";
11"GND\g";
12"VR_FET_SW_P12V_STBY_PVDDQ_DEF\g";
13"VR_PVNN_PCH_VINSEN";
14"PWRGD_PVNN_P1V05_PCH";
15"PWRGD_PVNN_PCH_R";
16"VID_PCH_CORE_PVNN_AUX_VID_0";
17"VID_PCH_CORE_PVNN_AUX_VID_1";
18"VR_PVNN_P1V05_PCH_VD12";
19"VR_PVNN_PCH_PWM1";
20"VR_P1V05_PCH_STBY_PWM1";
21"IRQ_PVNN_PCH_VRHOT_N";
22"TP_PVNN_PCH_PINALRT_N";
23"VR_PVNN_PCH_VDD";
24"VR_PVNN_PCH_AIREF1";
25"VR_PVNN_PCH_VREN";
26"TP_PVNN_PCH_VCLK";
27"PU_VR_PVNN_PCH_FAULT1";
28"TP_PVNN_PCH_MP2";
29"TP_PVNN_PCH_MP3";
30"NC_PVNN_PCH_DNC3";
31"TP_PVNN_PCH_SVID_ALERT";
32"NC_PVNN_PCH_DNC4";
33"NC_PVNN_PCH_DNC2";
34"NC_PVNN_PCH_DNC1";
35"NC_PVNN_PCH_DNC0";
36"VR_P1V05_PCH_STBY_AVSP";
37"VSENSE_PVNN_PCH_STBY_AVSN";
38"VR_PVNN_PCH_AVSP";
39"VSENSE_P1V05_PCH_STBY_AVSN";
40"VR_P1V05_PCH_BIREF1";
41"TP_VR_PVNN_PCH_AIINSEN";
42"VR_PVNN_PCH_XADDR2";
43"VR_PVNN_PCH_XADDR1";
44"TP_PVNN_PCH_RESET_N";
45"TP_PVNN_PCH_VDIO";
46"SMB_VR_SCL_PVNN_PCH";
47"SMB_VR_SDA_PVNN_PCH";
48"ISENSE_PVNN_PCH_PH1_IMON";
49"PWRGD_P1V8_PCH_STBY";
50"A_TSENSE_PVNN_PCH_TMON";
51"VR_PVNN_PCH_VINSEN";
52"VR_PVNN_P1V05_PCH_VD12";
53"SMB_VR_STBY_LVC3_SCL";
54"SMB_VR_STBY_LVC3_SDA";
55"ISENSE_P1V05_PCH_STBY_PH1_IMON";
56"A_TSENSE_P1V05_PCH_STBY_TMON";
57"VR_PVNN_P1V05_PCH_VD12";
58"VR_PVNN_P1V05_PCH_VD12";
59"VSENSE_P1V05_PCH_STBY_AVSP";
60"VSENSE_PVNN_PCH_STBY_AVSP";
%"P3V3_STBY"
"1","(-8375,5375)","0","mstr_symbols","I135";
;
SIZE"1B"
CDS_LIB"mstr_symbols"
BODY_TYPE"PLUMBING"
VOLTAGE"3.3V"
HDL_POWER"P3V3_STBY";
"G\NAC"1;
%"CAP_A"
"1","(-8800,1925)","0","dev_discrete","I143";
;
ROOM"PVNN_PCH_STBY"
SEC"1"
SEC_TYPE"0402V"
CDS_SEC"1"
CDS_LOCATION"C8A7"
CDS_LIB"dev_discrete"
LOCATION"C8A7"
PART_NUMBER"D97712-004"
VALUE"1.0UF"
TOLERANCE"10%"
PACK_TYPE"0402V"
VOLTAGE"6.3V"
MATERIAL"X6S";
"B"
$PN"2"2;
"A"
$PN"1"18;
%"GND"
"1","(-8800,1550)","0","mstr_symbols","I144";
;
CDS_LIB"mstr_symbols"
VOLTAGE"0"
HDL_POWER"GND"
SIZE"1B"
BODY_TYPE"PLUMBING"
ROOM"PVNN_PCH_STBY";
"A\NAC"2;
%"CAP_A"
"1","(-9200,1975)","0","dev_discrete","I145";
;
SEC"1"
SEC_TYPE"0402V"
CDS_SEC"1"
CDS_LOCATION"C8A8"
ROOM"PVNN_PCH_STBY"
CDS_LIB"dev_discrete"
LOCATION"C8A8"
VALUE"0.1UF"
PART_NUMBER"A36096-030"
TOLERANCE"10%"
VOLTAGE"16V"
MATERIAL"X7R"
PACK_TYPE"0402V";
"B"
$PN"2"3;
"A"
$PN"1"18;
%"GND"
"1","(-9200,1775)","0","mstr_symbols","I146";
;
HDL_POWER"GND"
CDS_LIB"mstr_symbols"
VOLTAGE"0"
SIZE"1B"
BODY_TYPE"PLUMBING"
ROOM"PVNN_PCH_STBY";
"A\NAC"3;
%"RES"
"1","(-7100,4500)","0","mstr_discrete","I147";
;
CDS_SEC"1"
SEC"1"
SEC_TYPE"0402"
ROOM"PVNN_PCH_STBY"
CDS_LOCATION"R2L16"
CDS_LIB"mstr_discrete"
PART_NUMBER"G21796-250"
LOCATION"R2L16"
TOLERANCE"1.0%"
MATERIAL"CHIP"
PACK_TYPE"0402"
VALUE"22.1"
WATTAGE"1/16W";
"B"
$PN"2"14;
"A"
$PN"1"15;
%"RES"
"2","(-8525,4800)","0","mstr_discrete","I148";
;
CDS_SEC"1"
CDS_LOCATION"R2L24"
SEC_TYPE"0402"
SEC"1"
CDS_LIB"mstr_discrete"
ROOM"PVNN_PCH_STBY"
MATERIAL"EMPTY"
LOCATION"R2L24"
PART_NUMBER"G21796-311"
VALUE"2.26K"
TOLERANCE"1.0%"
PACK_TYPE"0402"
WATTAGE"1/16W";
"A"
$PN"1"1;
"B"
$PN"2"27;
%"RES"
"2","(-9025,4875)","0","mstr_discrete","I149";
;
CDS_SEC"1"
SEC_TYPE"0402"
ROOM"PVNN_PCH_STBY"
SEC"1"
CDS_LIB"mstr_discrete"
CDS_LOCATION"R8A6"
PART_NUMBER"G21796-026"
VALUE"1.00K"
MATERIAL"CHIP"
LOCATION"R8A6"
WATTAGE"1/16W"
TOLERANCE"1%"
PACK_TYPE"0402";
"A"
$PN"1"1;
"B"
$PN"2"15;
%"CAP_A"
"1","(-9750,5075)","0","dev_discrete","I151";
;
CDS_SEC"1"
CDS_LOCATION"C2L8"
SEC_TYPE"0402V"
SEC"1"
ROOM"PVNN_PCH_STBY"
CDS_LIB"dev_discrete"
VALUE"1.0UF"
LOCATION"C2L8"
PART_NUMBER"D97712-004"
TOLERANCE"10%"
PACK_TYPE"0402V"
VOLTAGE"6.3V"
MATERIAL"X6S";
"B"
$PN"2"4;
"A"
$PN"1"23;
%"GND"
"1","(-9750,4875)","0","mstr_symbols","I152";
;
SIZE"1B"
HDL_POWER"GND"
CDS_LIB"mstr_symbols"
VOLTAGE"0"
BODY_TYPE"PLUMBING"
ROOM"PVNN_PCH_STBY";
"A\NAC"4;
%"CAP"
"1","(-12475,2075)","0","mstr_discrete","I153";
;
CDS_SEC"1"
SEC_TYPE"0402LF"
SEC"1"
NO_XNET_CONNECTION"1"
ROOM"PVNN_PCH_STBY"
CDS_LOCATION"C2L2"
CDS_LIB"mstr_discrete"
TOLERANCE"10%"
PART_NUMBER"A36096-050"
VALUE"220PF"
PACK_TYPE"0402LF"
MATERIAL"X7R"
VOLTAGE"50V"
LOCATION"C2L2";
"A"
$PN"1"36;
"B"
$PN"2"39;
%"RES"
"1","(-12675,2225)","0","mstr_discrete","I154";
;
CDS_SEC"1"
ROOM"PVNN_PCH_STBY"
SEC"1"
SEC_TYPE"0603"
CDS_LOCATION"R2L8"
CDS_LIB"mstr_discrete"
PACK_TYPE"0603"
MATERIAL"CHIP"
LOCATION"R2L8"
TOLERANCE"1%"
PART_NUMBER"G22026-041"
VALUE"10.0"
WATTAGE"1/10W";
"B"
$PN"2"36;
"A"
$PN"1"59;
%"GND"
"1","(-8900,2800)","0","mstr_symbols","I155";
;
HDL_POWER"GND"
VOLTAGE"0"
CDS_LIB"mstr_symbols"
SIZE"1B"
BODY_TYPE"PLUMBING"
ROOM"PVNN_PCH_STBY";
"A\NAC"5;
%"P3V3_STBY"
"1","(-10450,5750)","0","mstr_symbols","I158";
;
VOLTAGE"3.3V"
SIZE"1B"
CDS_LIB"mstr_symbols"
BODY_TYPE"PLUMBING"
HDL_POWER"P3V3_STBY";
"G\NAC"6;
%"RES"
"2","(-10450,5425)","0","mstr_discrete","I159";
;
CDS_SEC"1"
SEC_TYPE"0402"
ROOM"PVNN_PCH_STBY"
SEC"1"
CDS_LOCATION"R2L14"
CDS_LIB"mstr_discrete"
PART_NUMBER"G21497-005"
TOLERANCE"5%"
VALUE"0.0"
LOCATION"R2L14"
WATTAGE"1/16W"
PACK_TYPE"0402"
MATERIAL"CHIP";
"A"
$PN"1"6;
"B"
$PN"2"23;
%"RES"
"2","(-12325,5500)","0","mstr_discrete","I165";
;
CDS_SEC"1"
SEC_TYPE"0402"
SEC"1"
ROOM"PVNN_PCH_STBY"
CDS_LIB"mstr_discrete"
CDS_LOCATION"R8A4"
PART_NUMBER"G21796-160"
VALUE"100.0K"
TOLERANCE"1%"
PACK_TYPE"0402"
MATERIAL"CHIP"
WATTAGE"1/16W"
LOCATION"R8A4";
"A"
$PN"1"12;
"B"
$PN"2"13;
%"RES"
"2","(-12325,5175)","0","mstr_discrete","I166";
;
CDS_SEC"1"
SEC_TYPE"0402"
SEC"1"
ROOM"PVNN_PCH_STBY"
CDS_LIB"mstr_discrete"
CDS_LOCATION"R2L10"
VALUE"1.5K"
TOLERANCE"1%"
WATTAGE"1/16W"
MATERIAL"CHIP"
PART_NUMBER"G21796-003"
PACK_TYPE"0402"
LOCATION"R2L10";
"A"
$PN"1"13;
"B"
$PN"2"9;
%"CAP"
"1","(-12550,5175)","2","mstr_discrete","I167";
;
CDS_SEC"1"
SEC"1"
SEC_TYPE"0402LF"
ROOM"PVNN_PCH_STBY"
CDS_LIB"mstr_discrete"
CDS_LOCATION"C8A3"
LOCATION"C8A3"
VALUE"1000PF"
PART_NUMBER"A36096-046"
TOLERANCE"10%"
VOLTAGE"50V"
PACK_TYPE"0402LF"
MATERIAL"X7R";
"A"
$PN"1"13;
"B"
$PN"2"10;
%"CAP_A"
"1","(-10150,5075)","0","dev_discrete","I169";
;
SEC"1"
SEC_TYPE"0402V"
CDS_SEC"1"
CDS_LOCATION"C2L11"
ROOM"PVNN_PCH_STBY"
CDS_LIB"dev_discrete"
VALUE"0.1UF"
LOCATION"C2L11"
PART_NUMBER"A36096-030"
PACK_TYPE"0402V"
TOLERANCE"10%"
VOLTAGE"16V"
MATERIAL"X7R";
"B"
$PN"2"7;
"A"
$PN"1"23;
%"GND"
"1","(-10150,4875)","0","mstr_symbols","I170";
;
HDL_POWER"GND"
VOLTAGE"0"
CDS_LIB"mstr_symbols"
SIZE"1B"
BODY_TYPE"PLUMBING"
ROOM"PVNN_PCH_STBY";
"A\NAC"7;
%"RES"
"1","(-11075,3350)","0","mstr_discrete","I172";
;
CDS_SEC"1"
$SEC"1"
CDS_LIB"mstr_discrete"
CDS_LOCATION"R8A8"
ROOM"PVNN_PCH_STBY"
PACK_TYPE"0402"
PART_NUMBER"G21796-173"
MATERIAL"CHIP"
LOCATION"R8A8"
WATTAGE"1/16W"
TOLERANCE"1%"
VALUE"20.0";
"B"
$PN"2"47;
"A"
$PN"1"54;
%"RES"
"1","(-11400,3300)","0","mstr_discrete","I173";
;
ROOM"PVNN_PCH_STBY"
CDS_LOCATION"R8A9"
$SEC"1"
CDS_SEC"1"
CDS_LIB"mstr_discrete"
PART_NUMBER"G21796-173"
PACK_TYPE"0402"
LOCATION"R8A9"
TOLERANCE"1%"
MATERIAL"CHIP"
WATTAGE"1/16W"
VALUE"20.0";
"B"
$PN"2"46;
"A"
$PN"1"53;
%"RES"
"2","(-10750,2250)","0","mstr_discrete","I176";
;
CDS_SEC"1"
ROOM"PVNN_PCH_STBY"
CDS_LOCATION"R2L9"
SEC"1"
SEC_TYPE"0402"
CDS_LIB"mstr_discrete"
PART_NUMBER"G21796-082"
VALUE"4.02K"
LOCATION"R2L9"
TOLERANCE"1%"
PACK_TYPE"0402"
MATERIAL"CHIP"
WATTAGE"1/16W";
"A"
$PN"1"43;
"B"
$PN"2"8;
%"GND"
"1","(-10750,1675)","0","mstr_symbols","I178";
;
HDL_POWER"GND"
VOLTAGE"0"
SIZE"1B"
CDS_LIB"mstr_symbols"
BODY_TYPE"PLUMBING"
ROOM"PVNN_PCH_STBY";
"A\NAC"8;
%"GND"
"1","(-12325,4925)","0","mstr_symbols","I181";
;
SIZE"1B"
HDL_POWER"GND"
BODY_TYPE"PLUMBING"
CDS_LIB"mstr_symbols"
VOLTAGE"0"
ROOM"PVNN_PCH_STBY";
"A\NAC"9;
%"GND"
"1","(-12550,4925)","0","mstr_symbols","I183";
;
HDL_POWER"GND"
SIZE"1B"
VOLTAGE"0"
CDS_LIB"mstr_symbols"
BODY_TYPE"PLUMBING"
ROOM"PVNN_PCH_STBY";
"A\NAC"10;
%"CAP"
"1","(-12375,2600)","0","mstr_discrete","I209";
;
CDS_SEC"1"
SEC"1"
SEC_TYPE"0402LF"
ROOM"PVNN_PCH_STBY"
CDS_LOCATION"C8A2"
CDS_LIB"mstr_discrete"
TOLERANCE"10%"
MATERIAL"X7R"
LOCATION"C8A2"
PART_NUMBER"A36096-050"
VALUE"220PF"
PACK_TYPE"0402LF"
VOLTAGE"50V"
NO_XNET_CONNECTION"1";
"A"
$PN"1"38;
"B"
$PN"2"37;
%"RES"
"1","(-12675,2750)","0","mstr_discrete","I210";
;
CDS_SEC"1"
ROOM"PVNN_PCH_STBY"
SEC_TYPE"0402"
SEC"1"
CDS_LOCATION"R8A1"
CDS_LIB"mstr_discrete"
PACK_TYPE"0402"
MATERIAL"CHIP"
NO_XNET_CONNECTION"1"
LOCATION"R8A1"
TOLERANCE"1%"
PART_NUMBER"G21796-066"
VALUE"10.0"
WATTAGE"1/16W";
"B"
$PN"2"38;
"A"
$PN"1"60;
%"RES"
"2","(-8200,4875)","0","mstr_discrete","I216";
;
CDS_SEC"1"
$SEC"1"
CDS_LOCATION"R8A5"
CDS_LIB"mstr_discrete"
PART_NUMBER"G21796-026"
LOCATION"R8A5"
VALUE"1.00K"
TOLERANCE"1%"
PACK_TYPE"0402"
MATERIAL"CHIP"
WATTAGE"1/16W";
"A"
$PN"1"1;
"B"
$PN"2"21;
%"RES"
"2","(-10375,2275)","0","mstr_discrete","I217";
;
CDS_SEC"1"
CDS_LOCATION"R8A2"
$SEC"1"
CDS_LIB"mstr_discrete"
LOCATION"R8A2"
PART_NUMBER"G21796-180"
VALUE"2.67K"
PACK_TYPE"0402"
MATERIAL"CHIP"
WATTAGE"1/16W"
TOLERANCE"1%";
"A"
$PN"1"42;
"B"
$PN"2"8;
%"CAP"
"1","(-8000,4325)","0","mstr_discrete","I218";
;
CDS_SEC"1"
SEC_TYPE"0402LF"
SEC"1"
ROOM"PVNN_PCH_STBY"
CDS_LOCATION"C8A9"
CDS_LIB"mstr_discrete"
PART_NUMBER"A36096-046"
TOLERANCE"10%"
PACK_TYPE"0402LF"
VOLTAGE"50V"
VALUE"1000PF"
LOCATION"C8A9"
MATERIAL"X7R";
"A"
$PN"1"15;
"B"
$PN"2"11;
%"GND"
"1","(-8000,4075)","0","mstr_symbols","I219";
;
HDL_POWER"GND"
VOLTAGE"0"
CDS_LIB"mstr_symbols"
BODY_TYPE"PLUMBING"
SIZE"1B"
ROOM"PVNN_PCH_STBY";
"A\NAC"11;
%"RES"
"1","(-11800,4150)","0","mstr_discrete","I221";
;
CDS_SEC"1"
SEC_TYPE"0402"
SEC"1"
CDS_LIB"mstr_discrete"
CDS_LOCATION"R2L17"
ROOM"PVCCIN_CPU0_VR"
LOCATION"R2L17"
PART_NUMBER"G21497-005"
PACK_TYPE"0402"
MATERIAL"CHIP"
VALUE"0.0"
TOLERANCE"5%"
WATTAGE"1/16W";
"B"
$PN"2"25;
"A"
$PN"1"49;
%"RES"
"2","(-11175,5075)","0","mstr_discrete","I222";
;
CDS_SEC"1"
BOM_COST"SM_CONTROLLER"
SEC_TYPE"0402"
SEC"1"
CDS_LOCATION"R8A7"
ROOM"BMC"
CDS_LIB"mstr_discrete"
VALUE"100.0K"
LOCATION"R8A7"
TOLERANCE"1%"
MATERIAL"EMPTY"
PART_NUMBER"G21796-010"
WATTAGE"1/16W"
PACK_TYPE"0402";
"A"
$PN"1"6;
"B"
$PN"2"25;
%"RES"
"1","(-12350,4650)","0","mstr_discrete","I224";
;
CDS_SEC"1"
SEC_TYPE"0402"
SEC"1"
CDS_LIB"mstr_discrete"
CDS_LOCATION"R2L1"
ROOM"PVCCIN_CPU0_VR"
PACK_TYPE"0402"
LOCATION"R2L1"
PART_NUMBER"G21497-005"
MATERIAL"CHIP"
VALUE"0.0"
TOLERANCE"5%"
WATTAGE"1/16W";
"B"
$PN"2"24;
"A"
$PN"1"58;
%"RES"
"1","(-11525,2925)","0","mstr_discrete","I225";
;
$SEC"1"
CDS_SEC"1"
ROOM"PVCCIN_CPU0_VR"
CDS_LOCATION"R2L7"
CDS_LIB"mstr_discrete"
PACK_TYPE"0402"
PART_NUMBER"G21497-005"
TOLERANCE"5%"
LOCATION"R2L7"
MATERIAL"CHIP"
WATTAGE"1/16W"
VALUE"0.0";
"B"
$PN"2"40;
"A"
$PN"1"57;
%"VCC_CORE"
"1","(-12325,5750)","0","mstr_symbols","I228";
;
CDS_LIB"mstr_symbols"
HDL_POWER"VR_FET_SW_P12V_STBY_PVDDQ_DEF";
"A"12;
%"PXE1110B"
"1","(-9725,3750)","0","mstr_controller","I229";
;
CDS_SEC"1"
CDS_LOCATION"EU8A1"
SEC"1"
SEC_TYPE"QFN"
PACK_TYPE"QFN"
CDS_LIB"mstr_controller"
CDS_LMAN_SYM_OUTLINE"-400,850,400,-850"
LOCATION"EU8A1"
MATERIAL"IC"
PART_NUMBER"H89187-001";
"AVREN"
$PN"10"25;
"AVRRDY"
$PN"9"15;
"MP4"
$PN"32"27;
"MP3"
$PN"31"29;
"MP2"
$PN"18"28;
"MP1"
$PN"14"17;
"MP0"
$PN"13"16;
"DNC<3>"
$PN"24"30;
"VD12"
$PN"40"52;
"IINSEN"
$PN"38"41;
"VINSEN"
$PN"37"51;
"BVREF"
$PN"30"39;
"BVSEN"
$PN"29"36;
"AVREF"
$PN"20"37;
"AVSEN"
$PN"19"38;
"VALRT_N \B"
$PN"17"31;
"PINALRT_N \B"
$PN"12"22;
"VRHOT_N \B"
$PN"11"21;
"GND<1>"
$PN"23"5;
"GND<0>"
$PN"27"5;
"DNC<4>"
$PN"28"32;
"DNC<2>"
$PN"4"33;
"DNC<1>"
$PN"2"34;
"DNC<0>"
$PN"1"35;
"BIREF1"
$PN"25"40;
"BISEN1"
$PN"26"55;
"BTSEN"
$PN"34"56;
"VDD"
$PN"39"23;
"AIREF1"
$PN"21"24;
"AISEN1"
$PN"22"48;
"ATSEN"
$PN"35"50;
"XADDR2"
$PN"33"42;
"XADDR1"
$PN"36"43;
"RESET_N \B"
$PN"8"44;
"VDIO"
$PN"16"45;
"VCLK"
$PN"15"26;
"SCL"
$PN"7"46;
"SDA"
$PN"6"47;
"APWM1"
$PN"5"19;
"BPWM1"
$PN"3"20;
"THPAD"
$PN"41"5;
%"RES"
"2","(-7775,4875)","0","mstr_discrete","I235";
;
CDS_LOCATION"R2L25"
BOM_COST"SM_CONTROLLER"
CDS_SEC"1"
$SEC"1"
ROOM"BMC"
CDS_LIB"mstr_discrete"
MATERIAL"EMPTY"
LOCATION"R2L25"
PART_NUMBER"G21796-010"
VALUE"100.0K"
TOLERANCE"1%"
PACK_TYPE"0402"
WATTAGE"1/16W";
"A"
$PN"1"1;
"B"
$PN"2"17;
%"RES"
"2","(-7450,4950)","0","mstr_discrete","I236";
;
CDS_LOCATION"R2L26"
ROOM"BMC"
$SEC"1"
CDS_SEC"1"
BOM_COST"SM_CONTROLLER"
CDS_LIB"mstr_discrete"
PART_NUMBER"G21796-010"
MATERIAL"EMPTY"
LOCATION"R2L26"
VALUE"100.0K"
WATTAGE"1/16W"
TOLERANCE"1%"
PACK_TYPE"0402";
"A"
$PN"1"1;
"B"
$PN"2"16;
END.
